# BASEBOARD_FAB2 (Tioga Pass) — schematic netlist excerpt (pin names and nets, part order shuffled) for the footprints in the layout excerpt that follows; sources: Cadence DE-HDL packaged netlist, KiCad conversion of Wiwynn_Tioga_Pass_MB.brd

J1A1  SCONN288_H44441004  SCONN  pkg PIP  page 87
  \12v\(1)  = P12V_NVDIMM_KLM
  VSS(93)  = GND
  DQ(4)  = M_M_DQ<5>
  VSS(92)  = GND
  DQ(0)  = M_M_DQ<1>
  VSS(91)  = GND
  DQS9P  = M_M_DQS_DP<9>
  DQS9N  = M_M_DQS_DN<9>
  VSS(90)  = GND
  DQ(6)  = M_M_DQ<7>
  VSS(89)  = GND
  DQ(2)  = M_M_DQ<3>
  VSS(88)  = GND
  DQ(12)  = M_M_DQ<13>
  VSS(87)  = GND
  DQ(8)  = M_M_DQ<9>
  VSS(86)  = GND
  DQS10P  = M_M_DQS_DP<10>
  DQS10N  = M_M_DQS_DN<10>
  VSS(85)  = GND
  DQ(14)  = M_M_DQ<15>
  VSS(84)  = GND
  DQ(10)  = M_M_DQ<11>
  VSS(83)  = GND
  DQ(20)  = M_M_DQ<21>
  VSS(82)  = GND
  DQ(16)  = M_M_DQ<17>
  VSS(81)  = GND
  DQS11P  = M_M_DQS_DP<11>
  DQS11N  = M_M_DQS_DN<11>
  VSS(80)  = GND
  DQ(22)  = M_M_DQ<23>
  VSS(79)  = GND
  DQ(18)  = M_M_DQ<19>
  VSS(78)  = GND
  DQ(28)  = M_M_DQ<29>
  VSS(77)  = GND
  DQ(24)  = M_M_DQ<25>
  VSS(76)  = GND
  DQS12P  = M_M_DQS_DP<12>
  DQS12N  = M_M_DQS_DN<12>
  VSS(75)  = GND
  DQ(30)  = M_M_DQ<31>
  VSS(74)  = GND
  DQ(26)  = M_M_DQ<27>
  VSS(73)  = GND
  CB(4)  = M_M_ECC<5>
  VSS(72)  = GND
  CB(0)  = M_M_ECC<1>
  VSS(71)  = GND
  DQS17P  = M_M_DQS_DP<17>
  DQS17N  = M_M_DQS_DN<17>
  VSS(70)  = GND
  CB(6)  = M_M_ECC<7>
  VSS(69)  = GND
  CB(2)  = M_M_ECC<3>
  VSS(68)  = GND
  RESET_N  = M_KLM_RST_N
  VDD(25)  = PVDDQ_KLM
  CKE(0)  = M_M_CKE<0>
  VDD(24)  = PVDDQ_KLM
  ACT_N  = M_M_ACT_N
  BG(0)  = M_M_BG<0>
  VDD(23)  = PVDDQ_KLM
  A12  = M_M_MA<12>
  A9  = M_M_MA<9>
  VDD(22)  = PVDDQ_KLM
  A8  = M_M_MA<8>
  A6  = M_M_MA<6>
  VDD(21)  = PVDDQ_KLM
  A3  = M_M_MA<3>
  A1  = M_M_MA<1>
  VDD(20)  = PVDDQ_KLM
  CK0P  = M_M_CLK_DP<0>
  CK0N  = M_M_CLK_DN<0>
  VDD(19)  = PVDDQ_KLM
  VTT(1)  = PVTT_KLM
  EVENT_N  = FM_DIMM_EVENT_COD_N
  A0  = M_M_MA<0>
  VDD(18)  = PVDDQ_KLM
  BA(0)  = M_M_BA<0>
  A16_RAS_N  = M_M_MA<16>
  VDD(17)  = PVDDQ_KLM
  S0_N  = M_M_CS_N<0>
  VDD(16)  = PVDDQ_KLM
  A15_CAS_N  = M_M_MA<15>
  ODT(0)  = M_M_ODT<0>
  VDD(15)  = PVDDQ_KLM
  S1_N  = M_M_CS_N<1>
  VDD(14)  = PVDDQ_KLM
  ODT(1)  = M_M_ODT<1>
  VDD(13)  = PVDDQ_KLM
  S2_N_C(0)  = M_M_CS_N<2>
  VSS(67)  = GND
  DQ(36)  = M_M_DQ<37>
  VSS(66)  = GND
  DQ(32)  = M_M_DQ<33>
  VSS(65)  = GND
  DQS13P  = M_M_DQS_DP<13>
  DQS13N  = M_M_DQS_DN<13>
  VSS(64)  = GND
  DQ(38)  = M_M_DQ<39>
  VSS(63)  = GND
  DQ(34)  = M_M_DQ<35>
  VSS(62)  = GND
  DQ(44)  = M_M_DQ<45>
  VSS(61)  = GND
  DQ(40)  = M_M_DQ<41>
  VSS(60)  = GND
  DQS14P  = M_M_DQS_DP<14>
  DQS14N  = M_M_DQS_DN<14>
  VSS(59)  = GND
  DQ(46)  = M_M_DQ<47>
  VSS(58)  = GND
  DQ(42)  = M_M_DQ<43>
  VSS(57)  = GND
  DQ(52)  = M_M_DQ<53>
  VSS(56)  = GND
  DQ(48)  = M_M_DQ<49>
  VSS(55)  = GND
  DQS15P  = M_M_DQS_DP<15>
  DQS15N  = M_M_DQS_DN<15>
  VSS(54)  = GND
  DQ(54)  = M_M_DQ<55>
  VSS(53)  = GND
  DQ(50)  = M_M_DQ<51>
  VSS(52)  = GND
  DQ(60)  = M_M_DQ<61>
  VSS(51)  = GND
  DQ(56)  = M_M_DQ<57>
  VSS(50)  = GND
  DQS16P  = M_M_DQS_DP<16>
  DQS16N  = M_M_DQS_DN<16>
  VSS(49)  = GND
  DQ(62)  = M_M_DQ<63>
  VSS(48)  = GND
  DQ(58)  = M_M_DQ<59>
  VSS(47)  = GND
  SA(0)  = GND
  SA(1)  = GND
  SCL  = SMB_DDR_KLM_VPP_SCL
  VPP(4)  = PVPP_KLM
  VPP(3)  = PVPP_KLM
  RFU(2)  = TP_CH_M_DIMM_M0_RFU_2
  \12v\(0)  = P12V_NVDIMM_KLM
  VREFCA  = M_M_VREF
  VSS(46)  = GND
  DQ(5)  = M_M_DQ<4>
  VSS(45)  = GND
  DQ(1)  = M_M_DQ<0>
  VSS(44)  = GND
  DQS0N  = M_M_DQS_DN<0>
  DQS0P  = M_M_DQS_DP<0>
  VSS(43)  = GND
  DQ(7)  = M_M_DQ<6>
  VSS(42)  = GND
  DQ(3)  = M_M_DQ<2>
  VSS(41)  = GND
  DQ(13)  = M_M_DQ<12>
  VSS(40)  = GND
  DQ(9)  = M_M_DQ<8>
  VSS(39)  = GND
  DQS1N  = M_M_DQS_DN<1>
  DQS1P  = M_M_DQS_DP<1>
  VSS(38)  = GND
  DQ(15)  = M_M_DQ<14>
  VSS(37)  = GND
  DQ(11)  = M_M_DQ<10>
  VSS(36)  = GND
  DQ(21)  = M_M_DQ<20>
  VSS(35)  = GND
  DQ(17)  = M_M_DQ<16>
  VSS(34)  = GND
  DQS2N  = M_M_DQS_DN<2>
  DQS2P  = M_M_DQS_DP<2>
  VSS(33)  = GND
  DQ(23)  = M_M_DQ<22>
  VSS(32)  = GND
  DQ(19)  = M_M_DQ<18>
  VSS(31)  = GND
  DQ(29)  = M_M_DQ<28>
  VSS(30)  = GND
  DQ(25)  = M_M_DQ<24>
  VSS(29)  = GND
  DQS3N  = M_M_DQS_DN<3>
  DQS3P  = M_M_DQS_DP<3>
  VSS(28)  = GND
  DQ(31)  = M_M_DQ<30>
  VSS(27)  = GND
  DQ(27)  = M_M_DQ<26>
  VSS(26)  = GND
  CB(5)  = M_M_ECC<4>
  VSS(25)  = GND
  CB(1)  = M_M_ECC<0>
  VSS(24)  = GND
  DQS8N  = M_M_DQS_DN<8>
  DQS8P  = M_M_DQS_DP<8>
  VSS(23)  = GND
  CB(7)  = M_M_ECC<6>
  VSS(22)  = GND
  CB(3)  = M_M_ECC<2>
  VSS(21)  = GND
  CKE(1)  = M_M_CKE<1>
  VDD(12)  = PVDDQ_KLM
  RFU(0)  = TP_CH_M_DIMM_M0_RFU_0
  VDD(11)  = PVDDQ_KLM
  BG(1)  = M_M_BG<1>
  ALERT_N  = M_M_ALERT_N
  VDD(10)  = PVDDQ_KLM
  A11  = M_M_MA<11>
  A7  = M_M_MA<7>
  VDD(9)  = PVDDQ_KLM
  A5  = M_M_MA<5>
  A4  = M_M_MA<4>
  VDD(8)  = PVDDQ_KLM
  A2  = M_M_MA<2>
  VDD(7)  = PVDDQ_KLM
  CK1P  = M_M_CLK_DP<1>
  CK1N  = M_M_CLK_DN<1>
  VDD(6)  = PVDDQ_KLM
  VTT(0)  = PVTT_KLM
  PAR  = M_M_PAR
  VDD(5)  = PVDDQ_KLM
  BA(1)  = M_M_BA<1>
  A10  = M_M_MA<10>
  VDD(4)  = PVDDQ_KLM
  RFU(1)  = TP_CH_M_DIMM_M0_RFU_1
  A14_WE_N  = M_M_MA<14>
  VDD(3)  = PVDDQ_KLM
  SAVE_N_NC  = FM_ADR_COMPLETE_KLM_N
  VDD(2)  = PVDDQ_KLM
  A13  = M_M_MA<13>
  VDD(1)  = PVDDQ_KLM
  A17  = M_M_MA<17>
  C(2)  = M_M_C<2>
  VDD(0)  = PVDDQ_KLM
  S3_N_C(1)  = M_M_CS_N<3>
  SA(2)  = PVPP_KLM
  VSS(20)  = GND
  DQ(37)  = M_M_DQ<36>
  VSS(19)  = GND
  DQ(33)  = M_M_DQ<32>
  VSS(18)  = GND
  DQS4N  = M_M_DQS_DN<4>
  DQS4P  = M_M_DQS_DP<4>
  VSS(17)  = GND
  DQ(39)  = M_M_DQ<38>
  VSS(16)  = GND
  DQ(35)  = M_M_DQ<34>
  VSS(15)  = GND
  DQ(45)  = M_M_DQ<44>
  VSS(14)  = GND
  DQ(41)  = M_M_DQ<40>
  VSS(13)  = GND
  DQS5N  = M_M_DQS_DN<5>
  DQS5P  = M_M_DQS_DP<5>
  VSS(12)  = GND
  DQ(47)  = M_M_DQ<46>
  VSS(11)  = GND
  DQ(43)  = M_M_DQ<42>
  VSS(10)  = GND
  DQ(53)  = M_M_DQ<52>
  VSS(9)  = GND
  DQ(49)  = M_M_DQ<48>
  VSS(8)  = GND
  DQS6N  = M_M_DQS_DN<6>
  DQS6P  = M_M_DQS_DP<6>
  VSS(7)  = GND
  DQ(55)  = M_M_DQ<54>
  VSS(6)  = GND
  DQ(51)  = M_M_DQ<50>
  VSS(5)  = GND
  DQ(61)  = M_M_DQ<60>
  VSS(4)  = GND
  DQ(57)  = M_M_DQ<56>
  VSS(3)  = GND
  DQS7N  = M_M_DQS_DN<7>
  DQS7P  = M_M_DQS_DP<7>
  VSS(2)  = GND
  DQ(63)  = M_M_DQ<62>
  VSS(1)  = GND
  DQ(59)  = M_M_DQ<58>
  VSS(0)  = GND
  VDDSPD  = PVPP_KLM
  SDA  = SMB_DDR_KLM_VPP_SDA
  VPP(1)  = PVPP_KLM
  VPP(0)  = PVPP_KLM
  VPP(2)  = PVPP_KLM

(kicad_pcb
	(version 20260206)
	(generator "pcbnew")
	(generator_version "10.0")
	(general
		(thickness 1.6)
		(legacy_teardrops no)
	)
	(paper "A4")
	(title_block
		(title "Wiwynn_Tioga_Pass_MB.brd")
		(comment 1 "Tioga Pass / footprint 830 of 4770 (J1A1), pads 153-202 of 291")
	)
	(layers
		(0 "F.Cu" signal "TOP")
		(4 "In1.Cu" signal "L2GND")
		(6 "In2.Cu" signal "L3")
		(8 "In3.Cu" signal "L4GND")
		(10 "In4.Cu" signal "L5")
		(12 "In5.Cu" signal "L6GND")
		(14 "In6.Cu" signal "L7VCC")
		(16 "In7.Cu" signal "L8VCC")
		(18 "In8.Cu" signal "L9GND")
		(20 "In9.Cu" signal "L10")
		(22 "In10.Cu" signal "L11GND")
		(24 "In11.Cu" signal "L12")
		(26 "In12.Cu" signal "L13GND")
		(2 "B.Cu" signal "BOTTOM")
		(9 "F.Adhes" user "F.Adhesive")
		(11 "B.Adhes" user "B.Adhesive")
		(13 "F.Paste" user "Package Geometry/Pastemask Top")
		(15 "B.Paste" user "Package Geometry/Pastemask Bottom")
		(5 "F.SilkS" user "Ref Des/Silkscreen Top")
		(7 "B.SilkS" user "Ref Des/Silkscreen Bottom")
		(1 "F.Mask" user "Board Geometry/Soldermask Top")
		(3 "B.Mask" user "Board Geometry/Soldermask Bottom")
		(17 "Dwgs.User" user "User.Drawings")
		(19 "Cmts.User" user "User.Comments")
		(21 "Eco1.User" user "User.Eco1")
		(23 "Eco2.User" user "User.Eco2")
		(25 "Edge.Cuts" user "Board Geometry/Outline")
		(27 "Margin" user)
		(31 "F.CrtYd" user "Package Geometry/Place Bound Top")
		(29 "B.CrtYd" user "Package Geometry/Place Bound Bottom")
		(35 "F.Fab" user "Ref Des/Assembly Top")
		(33 "B.Fab" user "Ref Des/Assembly Bottom")
	)
	(footprint ""
		(layer "F.Cu")
		(at 29.699458 -152.273 90)
		(property "Reference" "J1A1"
			(at -2.572512 42.563542 0)
			(unlocked yes)
			(layer "F.SilkS")
			(effects
				(font
					(size 0.7874 0.5842)
					(thickness 0.1524)
				)
				(justify left)
			)
		)
		(property "Value" ""
			(at 0 0 90)
			(layer "F.Fab")
			(effects
				(font
					(size 1.27 1.27)
				)
			)
		)
		(duplicate_pad_numbers_are_jumpers no)
		(pad "150" smd rect
			(at 4.59994 4.249928 90)
			(size 1.8034 0.508)
			(layers "F.Cu" "F.Mask" "F.Paste")
			(net "M_M_DQ<0>")
		)
		(pad "151" smd rect
			(at 4.59994 5.100066 90)
			(size 1.8034 0.508)
			(layers "F.Cu" "F.Mask" "F.Paste")
			(net "GND")
		)
		(pad "152" smd rect
			(at 4.59994 5.94995 90)
			(size 1.8034 0.508)
			(layers "F.Cu" "F.Mask" "F.Paste")
			(net "M_M_DQS_DN<0>")
		)
		(pad "153" smd rect
			(at 4.59994 6.800088 90)
			(size 1.8034 0.508)
			(layers "F.Cu" "F.Mask" "F.Paste")
			(net "M_M_DQS_DP<0>")
		)
		(pad "154" smd rect
			(at 4.59994 7.649972 90)
			(size 1.8034 0.508)
			(layers "F.Cu" "F.Mask" "F.Paste")
			(net "GND")
		)
		(pad "155" smd rect
			(at 4.59994 8.50011 90)
			(size 1.8034 0.508)
			(layers "F.Cu" "F.Mask" "F.Paste")
			(net "M_M_DQ<6>")
		)
		(pad "156" smd rect
			(at 4.59994 9.349994 90)
			(size 1.8034 0.508)
			(layers "F.Cu" "F.Mask" "F.Paste")
			(net "GND")
		)
		(pad "157" smd rect
			(at 4.59994 10.199878 90)
			(size 1.8034 0.508)
			(layers "F.Cu" "F.Mask" "F.Paste")
			(net "M_M_DQ<2>")
		)
		(pad "158" smd rect
			(at 4.59994 11.050016 90)
			(size 1.8034 0.508)
			(layers "F.Cu" "F.Mask" "F.Paste")
			(net "GND")
		)
		(pad "159" smd rect
			(at 4.59994 11.8999 90)
			(size 1.8034 0.508)
			(layers "F.Cu" "F.Mask" "F.Paste")
			(net "M_M_DQ<12>")
		)
		(pad "160" smd rect
			(at 4.59994 12.750038 90)
			(size 1.8034 0.508)
			(layers "F.Cu" "F.Mask" "F.Paste")
			(net "GND")
		)
		(pad "161" smd rect
			(at 4.59994 13.599922 90)
			(size 1.8034 0.508)
			(layers "F.Cu" "F.Mask" "F.Paste")
			(net "M_M_DQ<8>")
		)
		(pad "162" smd rect
			(at 4.59994 14.45006 90)
			(size 1.8034 0.508)
			(layers "F.Cu" "F.Mask" "F.Paste")
			(net "GND")
		)
		(pad "163" smd rect
			(at 4.59994 15.299944 90)
			(size 1.8034 0.508)
			(layers "F.Cu" "F.Mask" "F.Paste")
			(net "M_M_DQS_DN<1>")
		)
		(pad "164" smd rect
			(at 4.59994 16.150082 90)
			(size 1.8034 0.508)
			(layers "F.Cu" "F.Mask" "F.Paste")
			(net "M_M_DQS_DP<1>")
		)
		(pad "165" smd rect
			(at 4.59994 16.999966 90)
			(size 1.8034 0.508)
			(layers "F.Cu" "F.Mask" "F.Paste")
			(net "GND")
		)
		(pad "166" smd rect
			(at 4.59994 17.850104 90)
			(size 1.8034 0.508)
			(layers "F.Cu" "F.Mask" "F.Paste")
			(net "M_M_DQ<14>")
		)
		(pad "167" smd rect
			(at 4.59994 18.699988 90)
			(size 1.8034 0.508)
			(layers "F.Cu" "F.Mask" "F.Paste")
			(net "GND")
		)
		(pad "168" smd rect
			(at 4.59994 19.550126 90)
			(size 1.8034 0.508)
			(layers "F.Cu" "F.Mask" "F.Paste")
			(net "M_M_DQ<10>")
		)
		(pad "169" smd rect
			(at 4.59994 20.40001 90)
			(size 1.8034 0.508)
			(layers "F.Cu" "F.Mask" "F.Paste")
			(net "GND")
		)
		(pad "170" smd rect
			(at 4.59994 21.249894 90)
			(size 1.8034 0.508)
			(layers "F.Cu" "F.Mask" "F.Paste")
			(net "M_M_DQ<20>")
		)
		(pad "171" smd rect
			(at 4.59994 22.100032 90)
			(size 1.8034 0.508)
			(layers "F.Cu" "F.Mask" "F.Paste")
			(net "GND")
		)
		(pad "172" smd rect
			(at 4.59994 22.949916 90)
			(size 1.8034 0.508)
			(layers "F.Cu" "F.Mask" "F.Paste")
			(net "M_M_DQ<16>")
		)
		(pad "173" smd rect
			(at 4.59994 23.800054 90)
			(size 1.8034 0.508)
			(layers "F.Cu" "F.Mask" "F.Paste")
			(net "GND")
		)
		(pad "174" smd rect
			(at 4.59994 24.649938 90)
			(size 1.8034 0.508)
			(layers "F.Cu" "F.Mask" "F.Paste")
			(net "M_M_DQS_DN<2>")
		)
		(pad "175" smd rect
			(at 4.59994 25.500076 90)
			(size 1.8034 0.508)
			(layers "F.Cu" "F.Mask" "F.Paste")
			(net "M_M_DQS_DP<2>")
		)
		(pad "176" smd rect
			(at 4.59994 26.34996 90)
			(size 1.8034 0.508)
			(layers "F.Cu" "F.Mask" "F.Paste")
			(net "GND")
		)
		(pad "177" smd rect
			(at 4.59994 27.200098 90)
			(size 1.8034 0.508)
			(layers "F.Cu" "F.Mask" "F.Paste")
			(net "M_M_DQ<22>")
		)
		(pad "178" smd rect
			(at 4.59994 28.049982 90)
			(size 1.8034 0.508)
			(layers "F.Cu" "F.Mask" "F.Paste")
			(net "GND")
		)
		(pad "179" smd rect
			(at 4.59994 28.90012 90)
			(size 1.8034 0.508)
			(layers "F.Cu" "F.Mask" "F.Paste")
			(net "M_M_DQ<18>")
		)
		(pad "180" smd rect
			(at 4.59994 29.750004 90)
			(size 1.8034 0.508)
			(layers "F.Cu" "F.Mask" "F.Paste")
			(net "GND")
		)
		(pad "181" smd rect
			(at 4.59994 30.599888 90)
			(size 1.8034 0.508)
			(layers "F.Cu" "F.Mask" "F.Paste")
			(net "M_M_DQ<28>")
		)
		(pad "182" smd rect
			(at 4.59994 31.450026 90)
			(size 1.8034 0.508)
			(layers "F.Cu" "F.Mask" "F.Paste")
			(net "GND")
		)
		(pad "183" smd rect
			(at 4.59994 32.29991 90)
			(size 1.8034 0.508)
			(layers "F.Cu" "F.Mask" "F.Paste")
			(net "M_M_DQ<24>")
		)
		(pad "184" smd rect
			(at 4.59994 33.150048 90)
			(size 1.8034 0.508)
			(layers "F.Cu" "F.Mask" "F.Paste")
			(net "GND")
		)
		(pad "185" smd rect
			(at 4.59994 33.999932 90)
			(size 1.8034 0.508)
			(layers "F.Cu" "F.Mask" "F.Paste")
			(net "M_M_DQS_DN<3>")
		)
		(pad "186" smd rect
			(at 4.59994 34.85007 90)
			(size 1.8034 0.508)
			(layers "F.Cu" "F.Mask" "F.Paste")
			(net "M_M_DQS_DP<3>")
		)
		(pad "187" smd rect
			(at 4.59994 35.699954 90)
			(size 1.8034 0.508)
			(layers "F.Cu" "F.Mask" "F.Paste")
			(net "GND")
		)
		(pad "188" smd rect
			(at 4.59994 36.550092 90)
			(size 1.8034 0.508)
			(layers "F.Cu" "F.Mask" "F.Paste")
			(net "M_M_DQ<30>")
		)
		(pad "189" smd rect
			(at 4.59994 37.399976 90)
			(size 1.8034 0.508)
			(layers "F.Cu" "F.Mask" "F.Paste")
			(net "GND")
		)
		(pad "190" smd rect
			(at 4.59994 38.250114 90)
			(size 1.8034 0.508)
			(layers "F.Cu" "F.Mask" "F.Paste")
			(net "M_M_DQ<26>")
		)
		(pad "191" smd rect
			(at 4.59994 39.099998 90)
			(size 1.8034 0.508)
			(layers "F.Cu" "F.Mask" "F.Paste")
			(net "GND")
		)
		(pad "192" smd rect
			(at 4.59994 39.949882 90)
			(size 1.8034 0.508)
			(layers "F.Cu" "F.Mask" "F.Paste")
			(net "M_M_ECC<4>")
		)
		(pad "193" smd rect
			(at 4.59994 40.80002 90)
			(size 1.8034 0.508)
			(layers "F.Cu" "F.Mask" "F.Paste")
			(net "GND")
		)
		(pad "194" smd rect
			(at 4.59994 41.649904 90)
			(size 1.8034 0.508)
			(layers "F.Cu" "F.Mask" "F.Paste")
			(net "M_M_ECC<0>")
		)
		(pad "195" smd rect
			(at 4.59994 42.500042 90)
			(size 1.8034 0.508)
			(layers "F.Cu" "F.Mask" "F.Paste")
			(net "GND")
		)
		(pad "196" smd rect
			(at 4.59994 43.349926 90)
			(size 1.8034 0.508)
			(layers "F.Cu" "F.Mask" "F.Paste")
			(net "M_M_DQS_DN<8>")
		)
		(pad "197" smd rect
			(at 4.59994 44.200064 90)
			(size 1.8034 0.508)
			(layers "F.Cu" "F.Mask" "F.Paste")
			(net "M_M_DQS_DP<8>")
		)
		(pad "198" smd rect
			(at 4.59994 45.049948 90)
			(size 1.8034 0.508)
			(layers "F.Cu" "F.Mask" "F.Paste")
			(net "GND")
		)
		(pad "199" smd rect
			(at 4.59994 45.900086 90)
			(size 1.8034 0.508)
			(layers "F.Cu" "F.Mask" "F.Paste")
			(net "M_M_ECC<6>")
		)
	)
)
